# T6G (Grand Teton) — schematic netlist excerpt (pin names and nets, part order shuffled) for the footprints in the layout excerpt that follows; sources: Cadence DE-HDL packaged netlist, KiCad conversion of 04192023_DAF0TMB3IC0_F0TG_MB_C_brd_V02_OCP.brd

R3508  Q_RES  54.9K 1% CHIP  pkg 0402LF  page 130 : A = FM_GPU_PWR_EN_R1 ; B = GND
PC191  Q_CAP  560PF 50V 10% EMPTY  pkg C0402  page 202 : A = SW_PVDDCR_CPU1_P0_SW4 ; B = SW_PVDDCR_CPU1_P0_SW4_RC

(kicad_pcb
	(version 20260206)
	(generator "pcbnew")
	(generator_version "10.0")
	(general
		(thickness 1.6)
		(legacy_teardrops no)
	)
	(paper "A4")
	(title_block
		(title "04192023_DAF0TMB3IC0_F0TG_MB_C_brd_V02_OCP.brd")
		(comment 1 "Grand Teton / footprints 1442-1443 of 8354")
	)
	(layers
		(0 "F.Cu" signal "TOP")
		(4 "In1.Cu" signal "GND")
		(6 "In2.Cu" signal "IN1")
		(8 "In3.Cu" signal "GND1")
		(10 "In4.Cu" signal "IN2")
		(12 "In5.Cu" signal "GND2")
		(14 "In6.Cu" signal "IN3")
		(16 "In7.Cu" signal "GND3")
		(18 "In8.Cu" signal "VCC")
		(20 "In9.Cu" signal "VCC1")
		(22 "In10.Cu" signal "GND4")
		(24 "In11.Cu" signal "IN4")
		(26 "In12.Cu" signal "GND5")
		(28 "In13.Cu" signal "IN5")
		(30 "In14.Cu" signal "GND6")
		(32 "In15.Cu" signal "IN6")
		(34 "In16.Cu" signal "GND7")
		(2 "B.Cu" signal "BOTTOM")
		(9 "F.Adhes" user "F.Adhesive")
		(11 "B.Adhes" user "B.Adhesive")
		(13 "F.Paste" user "Package Geometry/Pastemask Top")
		(15 "B.Paste" user "Package Geometry/Pastemask Bottom")
		(5 "F.SilkS" user "Ref Des/Silkscreen Top")
		(7 "B.SilkS" user "Ref Des/Silkscreen Bottom")
		(1 "F.Mask" user "Board Geometry/Soldermask Top")
		(3 "B.Mask" user "Board Geometry/Soldermask Bottom")
		(17 "Dwgs.User" user "User.Drawings")
		(19 "Cmts.User" user "User.Comments")
		(21 "Eco1.User" user "User.Eco1")
		(23 "Eco2.User" user "User.Eco2")
		(25 "Edge.Cuts" user "Board Geometry/Outline")
		(27 "Margin" user)
		(31 "F.CrtYd" user "Package Geometry/Place Bound Top")
		(29 "B.CrtYd" user "Package Geometry/Place Bound Bottom")
		(35 "F.Fab" user "Ref Des/Assembly Top")
		(33 "B.Fab" user "Ref Des/Assembly Bottom")
	)
	(footprint ""
		(layer "F.Cu")
		(at 305.002184 -343.712038 180)
		(property "Reference" "PC191"
			(at 0 0 180)
			(layer "F.SilkS")
			(hide yes)
			(effects
				(font
					(size 1.27 1.27)
				)
			)
		)
		(property "Value" ""
			(at 0 0 180)
			(layer "F.Fab")
			(effects
				(font
					(size 1.27 1.27)
				)
			)
		)
		(duplicate_pad_numbers_are_jumpers no)
		(fp_line
			(start 0.7874 0.4064)
			(end -0.7874 0.4064)
			(stroke
				(width 0.1524)
				(type default)
			)
			(layer "F.SilkS")
		)
		(fp_line
			(start 0.7874 -0.4064)
			(end 0.7874 0.4064)
			(stroke
				(width 0.1524)
				(type default)
			)
			(layer "F.SilkS")
		)
		(fp_line
			(start -0.7874 0.4064)
			(end -0.7874 -0.4064)
			(stroke
				(width 0.1524)
				(type default)
			)
			(layer "F.SilkS")
		)
		(fp_line
			(start -0.7874 -0.4064)
			(end 0.7874 -0.4064)
			(stroke
				(width 0.1524)
				(type default)
			)
			(layer "F.SilkS")
		)
		(fp_line
			(start 0.67945 0.3048)
			(end 0.120396 0.3048)
			(stroke
				(width 0.1)
				(type default)
			)
			(layer "F.Fab")
		)
		(fp_line
			(start 0.67945 -0.3048)
			(end 0.67945 0.3048)
			(stroke
				(width 0.1)
				(type default)
			)
			(layer "F.Fab")
		)
		(fp_line
			(start 0.12065 -0.2794)
			(end 0.12065 -0.3048)
			(stroke
				(width 0.1)
				(type default)
			)
			(layer "F.Fab")
		)
		(fp_line
			(start 0.12065 -0.3048)
			(end 0.67945 -0.3048)
			(stroke
				(width 0.1)
				(type default)
			)
			(layer "F.Fab")
		)
		(fp_line
			(start 0.120396 0.3048)
			(end 0.120396 0.2794)
			(stroke
				(width 0.1)
				(type default)
			)
			(layer "F.Fab")
		)
		(fp_line
			(start 0.120396 0.2794)
			(end -0.12065 0.2794)
			(stroke
				(width 0.1)
				(type default)
			)
			(layer "F.Fab")
		)
		(fp_line
			(start -0.12065 0.3048)
			(end -0.67945 0.3048)
			(stroke
				(width 0.1)
				(type default)
			)
			(layer "F.Fab")
		)
		(fp_line
			(start -0.12065 0.2794)
			(end -0.12065 0.3048)
			(stroke
				(width 0.1)
				(type default)
			)
			(layer "F.Fab")
		)
		(fp_line
			(start -0.12065 -0.2794)
			(end 0.12065 -0.2794)
			(stroke
				(width 0.1)
				(type default)
			)
			(layer "F.Fab")
		)
		(fp_line
			(start -0.12065 -0.305054)
			(end -0.12065 -0.2794)
			(stroke
				(width 0.1)
				(type default)
			)
			(layer "F.Fab")
		)
		(fp_line
			(start -0.67945 0.3048)
			(end -0.67945 -0.305054)
			(stroke
				(width 0.1)
				(type default)
			)
			(layer "F.Fab")
		)
		(fp_line
			(start -0.67945 -0.305054)
			(end -0.12065 -0.305054)
			(stroke
				(width 0.1)
				(type default)
			)
			(layer "F.Fab")
		)
		(pad "1" smd circle
			(at -0.40005 0 180)
			(size 0 0)
			(layers "F.Cu" "F.Mask" "F.Paste")
			(net "SW_PVDDCR_CPU1_P0_SW4")
		)
		(pad "2" smd circle
			(at 0.40005 0 180)
			(size 0 0)
			(layers "F.Cu" "F.Mask" "F.Paste")
			(net "SW_PVDDCR_CPU1_P0_SW4_RC")
		)
	)
	(footprint ""
		(layer "F.Cu")
		(at 46.16704 -438.753504 90)
		(property "Reference" "R3508"
			(at 0 0 90)
			(layer "F.SilkS")
			(hide yes)
			(effects
				(font
					(size 1.27 1.27)
				)
			)
		)
		(property "Value" ""
			(at 0 0 90)
			(layer "F.Fab")
			(effects
				(font
					(size 1.27 1.27)
				)
			)
		)
		(duplicate_pad_numbers_are_jumpers no)
		(fp_line
			(start 0.7874 -0.4064)
			(end 0.7874 0.4064)
			(stroke
				(width 0.1524)
				(type default)
			)
			(layer "F.SilkS")
		)
		(fp_line
			(start -0.7874 -0.4064)
			(end 0.7874 -0.4064)
			(stroke
				(width 0.1524)
				(type default)
			)
			(layer "F.SilkS")
		)
		(fp_line
			(start 0.7874 0.4064)
			(end -0.7874 0.4064)
			(stroke
				(width 0.1524)
				(type default)
			)
			(layer "F.SilkS")
		)
		(fp_line
			(start -0.7874 0.4064)
			(end -0.7874 -0.4064)
			(stroke
				(width 0.1524)
				(type default)
			)
			(layer "F.SilkS")
		)
		(fp_line
			(start -0.12065 -0.305054)
			(end -0.12065 -0.2794)
			(stroke
				(width 0.1)
				(type default)
			)
			(layer "F.Fab")
		)
		(fp_line
			(start -0.67945 -0.305054)
			(end -0.12065 -0.305054)
			(stroke
				(width 0.1)
				(type default)
			)
			(layer "F.Fab")
		)
		(fp_line
			(start 0.67945 -0.3048)
			(end 0.67945 0.3048)
			(stroke
				(width 0.1)
				(type default)
			)
			(layer "F.Fab")
		)
		(fp_line
			(start 0.12065 -0.3048)
			(end 0.67945 -0.3048)
			(stroke
				(width 0.1)
				(type default)
			)
			(layer "F.Fab")
		)
		(fp_line
			(start 0.12065 -0.2794)
			(end 0.12065 -0.3048)
			(stroke
				(width 0.1)
				(type default)
			)
			(layer "F.Fab")
		)
		(fp_line
			(start -0.12065 -0.2794)
			(end 0.12065 -0.2794)
			(stroke
				(width 0.1)
				(type default)
			)
			(layer "F.Fab")
		)
		(fp_line
			(start 0.120396 0.2794)
			(end -0.12065 0.2794)
			(stroke
				(width 0.1)
				(type default)
			)
			(layer "F.Fab")
		)
		(fp_line
			(start -0.12065 0.2794)
			(end -0.12065 0.3048)
			(stroke
				(width 0.1)
				(type default)
			)
			(layer "F.Fab")
		)
		(fp_line
			(start 0.67945 0.3048)
			(end 0.120396 0.3048)
			(stroke
				(width 0.1)
				(type default)
			)
			(layer "F.Fab")
		)
		(fp_line
			(start 0.120396 0.3048)
			(end 0.120396 0.2794)
			(stroke
				(width 0.1)
				(type default)
			)
			(layer "F.Fab")
		)
		(fp_line
			(start -0.12065 0.3048)
			(end -0.67945 0.3048)
			(stroke
				(width 0.1)
				(type default)
			)
			(layer "F.Fab")
		)
		(fp_line
			(start -0.67945 0.3048)
			(end -0.67945 -0.305054)
			(stroke
				(width 0.1)
				(type default)
			)
			(layer "F.Fab")
		)
		(pad "1" smd circle
			(at -0.40005 0 90)
			(size 0 0)
			(layers "F.Cu" "F.Mask" "F.Paste")
			(net "FM_GPU_PWR_EN_R1")
		)
		(pad "2" smd circle
			(at 0.40005 0 90)
			(size 0 0)
			(layers "F.Cu" "F.Mask" "F.Paste")
			(net "GND")
		)
	)
)
